# BASEBOARD_FAB2 (Tioga Pass) — schematic netlist excerpt (pin names and nets, part order shuffled) for the footprints in the layout excerpt that follows; sources: Cadence DE-HDL packaged netlist, KiCad conversion of Wiwynn_Tioga_Pass_MB.brd

C5G53  CAP_A  22.0UF 4V 20% X6S  pkg 0603V  page 242 : A = PVDDQ_ABC ; B = GND
R4P6  RES  240 1.0% EMPTY  pkg 0402  page 90 : A = GND ; B = PD_CPU0_DMIMODE_OVERRIDE
R2T38  RES  33.2 1% CHIP  pkg 0402  page 93 : A = FM_CPU0_PROCHOT_LVT3_K_N ; B = FM_CPU0_PROCHOT_LVT3_N

(kicad_pcb
	(version 20260206)
	(generator "pcbnew")
	(generator_version "10.0")
	(general
		(thickness 1.6)
		(legacy_teardrops no)
	)
	(paper "A4")
	(title_block
		(title "Wiwynn_Tioga_Pass_MB.brd")
		(comment 1 "Tioga Pass / footprints 3658-3660 of 4770")
	)
	(layers
		(0 "F.Cu" signal "TOP")
		(4 "In1.Cu" signal "L2GND")
		(6 "In2.Cu" signal "L3")
		(8 "In3.Cu" signal "L4GND")
		(10 "In4.Cu" signal "L5")
		(12 "In5.Cu" signal "L6GND")
		(14 "In6.Cu" signal "L7VCC")
		(16 "In7.Cu" signal "L8VCC")
		(18 "In8.Cu" signal "L9GND")
		(20 "In9.Cu" signal "L10")
		(22 "In10.Cu" signal "L11GND")
		(24 "In11.Cu" signal "L12")
		(26 "In12.Cu" signal "L13GND")
		(2 "B.Cu" signal "BOTTOM")
		(9 "F.Adhes" user "F.Adhesive")
		(11 "B.Adhes" user "B.Adhesive")
		(13 "F.Paste" user "Package Geometry/Pastemask Top")
		(15 "B.Paste" user "Package Geometry/Pastemask Bottom")
		(5 "F.SilkS" user "Ref Des/Silkscreen Top")
		(7 "B.SilkS" user "Ref Des/Silkscreen Bottom")
		(1 "F.Mask" user "Board Geometry/Soldermask Top")
		(3 "B.Mask" user "Board Geometry/Soldermask Bottom")
		(17 "Dwgs.User" user "User.Drawings")
		(19 "Cmts.User" user "User.Comments")
		(21 "Eco1.User" user "User.Eco1")
		(23 "Eco2.User" user "User.Eco2")
		(25 "Edge.Cuts" user "Board Geometry/Outline")
		(27 "Margin" user)
		(31 "F.CrtYd" user "Package Geometry/Place Bound Top")
		(29 "B.CrtYd" user "Package Geometry/Place Bound Bottom")
		(35 "F.Fab" user "Ref Des/Assembly Top")
		(33 "B.Fab" user "Ref Des/Assembly Bottom")
	)
	(footprint ""
		(layer "B.Cu")
		(at 361.444794 -44.845986 -90)
		(property "Reference" "R2T38"
			(at 0 0 90)
			(layer "B.SilkS")
			(hide yes)
			(effects
				(font
					(size 1.27 1.27)
				)
				(justify mirror)
			)
		)
		(property "Value" ""
			(at 0 0 90)
			(layer "B.Fab")
			(effects
				(font
					(size 1.27 1.27)
				)
				(justify mirror)
			)
		)
		(duplicate_pad_numbers_are_jumpers no)
		(fp_poly
			(pts
				(xy 0.2794 -0.1016) (xy -0.2794 -0.1016) (xy -0.2794 0.9906) (xy 0.2794 0.9906)
			)
			(stroke
				(width 0)
				(type default)
			)
			(fill no)
			(layer "B.CrtYd")
		)
		(fp_line
			(start -0.2794 0.9906)
			(end -0.2794 -0.1016)
			(stroke
				(width 0.1)
				(type default)
			)
			(layer "B.Fab")
		)
		(fp_line
			(start 0.2794 0.9906)
			(end -0.2794 0.9906)
			(stroke
				(width 0.1)
				(type default)
			)
			(layer "B.Fab")
		)
		(fp_line
			(start -0.2794 -0.1016)
			(end 0.2794 -0.1016)
			(stroke
				(width 0.1)
				(type default)
			)
			(layer "B.Fab")
		)
		(fp_line
			(start 0.2794 -0.1016)
			(end 0.2794 0.9906)
			(stroke
				(width 0.1)
				(type default)
			)
			(layer "B.Fab")
		)
		(pad "1" smd rect
			(at 0 0 90)
			(size 0.508 0.508)
			(layers "B.Cu" "B.Mask" "B.Paste")
			(net "FM_CPU0_PROCHOT_LVT3_K_N")
		)
		(pad "2" smd rect
			(at 0 0.889 90)
			(size 0.508 0.508)
			(layers "B.Cu" "B.Mask" "B.Paste")
			(net "FM_CPU0_PROCHOT_LVT3_N")
		)
		(zone
			(layer "B.Cu")
			(hatch none 0.5)
			(connect_pads
				(clearance 0)
			)
			(min_thickness 0.25)
			(keepout
				(tracks not_allowed)
				(vias allowed)
				(pads allowed)
				(copperpour not_allowed)
				(footprints allowed)
			)
			(placement
				(enabled no)
				(sheetname "")
			)
			(fill
				(thermal_gap 0.5)
				(thermal_bridge_width 0.5)
				(island_removal_mode 0)
			)
			(polygon
				(pts
					(xy 360.809794 -44.591986) (xy 360.809794 -45.099986) (xy 361.190794 -45.099986) (xy 361.190794 -44.591986)
				)
			)
		)
		(zone
			(layer "B.Cu")
			(hatch none 0.5)
			(connect_pads
				(clearance 0)
			)
			(min_thickness 0.25)
			(keepout
				(tracks allowed)
				(vias not_allowed)
				(pads allowed)
				(copperpour not_allowed)
				(footprints allowed)
			)
			(placement
				(enabled no)
				(sheetname "")
			)
			(fill
				(thermal_gap 0.5)
				(thermal_bridge_width 0.5)
				(island_removal_mode 0)
			)
			(polygon
				(pts
					(xy 361.190794 -44.591986) (xy 361.190794 -45.099986) (xy 360.809794 -45.099986) (xy 360.809794 -44.591986)
				)
			)
		)
	)
	(footprint ""
		(layer "B.Cu")
		(at 281.3812 -75.7174 90)
		(property "Reference" "R4P6"
			(at 0 0 90)
			(layer "B.SilkS")
			(hide yes)
			(effects
				(font
					(size 1.27 1.27)
				)
				(justify mirror)
			)
		)
		(property "Value" ""
			(at 0 0 90)
			(layer "B.Fab")
			(effects
				(font
					(size 1.27 1.27)
				)
				(justify mirror)
			)
		)
		(duplicate_pad_numbers_are_jumpers no)
		(fp_rect
			(start -0.2794 -0.1016)
			(end 0.2794 0.9906)
			(stroke
				(width 0)
				(type default)
			)
			(fill no)
			(layer "B.CrtYd")
		)
		(fp_line
			(start 0.2794 -0.1016)
			(end 0.2794 0.9906)
			(stroke
				(width 0.1)
				(type default)
			)
			(layer "B.Fab")
		)
		(fp_line
			(start -0.2794 -0.1016)
			(end 0.2794 -0.1016)
			(stroke
				(width 0.1)
				(type default)
			)
			(layer "B.Fab")
		)
		(fp_line
			(start 0.2794 0.9906)
			(end -0.2794 0.9906)
			(stroke
				(width 0.1)
				(type default)
			)
			(layer "B.Fab")
		)
		(fp_line
			(start -0.2794 0.9906)
			(end -0.2794 -0.1016)
			(stroke
				(width 0.1)
				(type default)
			)
			(layer "B.Fab")
		)
		(pad "1" smd rect
			(at 0 0 270)
			(size 0.508 0.508)
			(layers "B.Cu" "B.Mask" "B.Paste")
			(net "GND")
		)
		(pad "2" smd rect
			(at 0 0.889 270)
			(size 0.508 0.508)
			(layers "B.Cu" "B.Mask" "B.Paste")
			(net "PD_CPU0_DMIMODE_OVERRIDE")
		)
		(zone
			(layer "B.Cu")
			(hatch none 0.5)
			(connect_pads
				(clearance 0)
			)
			(min_thickness 0.25)
			(keepout
				(tracks not_allowed)
				(vias allowed)
				(pads allowed)
				(copperpour not_allowed)
				(footprints allowed)
			)
			(placement
				(enabled no)
				(sheetname "")
			)
			(fill
				(thermal_gap 0.5)
				(thermal_bridge_width 0.5)
				(island_removal_mode 0)
			)
			(polygon
				(pts
					(xy 281.6352 -75.4634) (xy 282.0162 -75.4634) (xy 282.0162 -75.9714) (xy 281.6352 -75.9714)
				)
			)
		)
		(zone
			(layer "B.Cu")
			(hatch none 0.5)
			(connect_pads
				(clearance 0)
			)
			(min_thickness 0.25)
			(keepout
				(tracks allowed)
				(vias not_allowed)
				(pads allowed)
				(copperpour not_allowed)
				(footprints allowed)
			)
			(placement
				(enabled no)
				(sheetname "")
			)
			(fill
				(thermal_gap 0.5)
				(thermal_bridge_width 0.5)
				(island_removal_mode 0)
			)
			(polygon
				(pts
					(xy 281.6352 -75.4634) (xy 282.0162 -75.4634) (xy 282.0162 -75.9714) (xy 281.6352 -75.9714)
				)
			)
		)
	)
	(footprint ""
		(layer "B.Cu")
		(at 253.392432 -3.3528 90)
		(property "Reference" "C5G53"
			(at -1.14681 0.76708 180)
			(unlocked yes)
			(layer "B.SilkS")
			(effects
				(font
					(size 0.7874 0.5842)
					(thickness 0.1524)
				)
				(justify mirror)
			)
		)
		(property "Value" ""
			(at 0 0 90)
			(layer "B.Fab")
			(effects
				(font
					(size 1.27 1.27)
				)
				(justify mirror)
			)
		)
		(duplicate_pad_numbers_are_jumpers no)
		(fp_rect
			(start -0.4953 -0.2032)
			(end 0.4953 1.6002)
			(stroke
				(width 0)
				(type default)
			)
			(fill no)
			(layer "B.CrtYd")
		)
		(fp_line
			(start 0.4953 -0.2032)
			(end -0.4953 -0.2032)
			(stroke
				(width 0.1)
				(type default)
			)
			(layer "B.Fab")
		)
		(fp_line
			(start -0.4953 -0.2032)
			(end -0.4953 1.6002)
			(stroke
				(width 0.1)
				(type default)
			)
			(layer "B.Fab")
		)
		(fp_line
			(start 0.4953 1.6002)
			(end 0.4953 -0.2032)
			(stroke
				(width 0.1)
				(type default)
			)
			(layer "B.Fab")
		)
		(fp_line
			(start -0.4953 1.6002)
			(end 0.4953 1.6002)
			(stroke
				(width 0.1)
				(type default)
			)
			(layer "B.Fab")
		)
		(pad "1" smd rect
			(at 0 0 270)
			(size 0.762 0.889)
			(layers "B.Cu" "B.Mask" "B.Paste")
			(net "PVDDQ_ABC")
		)
		(pad "2" smd rect
			(at 0 1.397 270)
			(size 0.762 0.889)
			(layers "B.Cu" "B.Mask" "B.Paste")
			(net "GND")
		)
		(zone
			(layer "B.Cu")
			(hatch none 0.5)
			(connect_pads
				(clearance 0)
			)
			(min_thickness 0.25)
			(keepout
				(tracks not_allowed)
				(vias allowed)
				(pads allowed)
				(copperpour not_allowed)
				(footprints allowed)
			)
			(placement
				(enabled no)
				(sheetname "")
			)
			(fill
				(thermal_gap 0.5)
				(thermal_bridge_width 0.5)
				(island_removal_mode 0)
			)
			(polygon
				(pts
					(xy 253.836932 -2.9718) (xy 254.344932 -2.9718) (xy 254.344932 -3.7338) (xy 253.836932 -3.7338)
				)
			)
		)
	)
)
